FILE_TYPE = CONNECTIVITY;
{Allegro Design Entry HDL 16.6-p007 (v16-6-112F) 10/10/2012}
"PAGE_NUMBER" = 75;
0"NC";
1"GND\g";
2"GND\g";
3"GND\g";
4"GND\g";
5"GND\g";
6"GND\g";
7"GND\g";
8"GND\g";
%"GND"
"1","(-5675,400)","0","mstr_symbols","I10";
;
VOLTAGE"0.0V"
CDS_LIB"mstr_symbols"
SIZE"1B"
BODY_TYPE"PLUMBING"
HDL_POWER"GND";
"A\NAC"1;
%"GND"
"1","(-3775,400)","0","mstr_symbols","I11";
;
VOLTAGE"0.0V"
SIZE"1B"
CDS_LIB"mstr_symbols"
BODY_TYPE"PLUMBING"
HDL_POWER"GND";
"A\NAC"2;
%"GND"
"1","(-1975,400)","0","mstr_symbols","I12";
;
VOLTAGE"0.0V"
SIZE"1B"
CDS_LIB"mstr_symbols"
BODY_TYPE"PLUMBING"
HDL_POWER"GND";
"A\NAC"3;
%"GND"
"1","(-2275,400)","0","mstr_symbols","I13";
;
VOLTAGE"0.0V"
CDS_LIB"mstr_symbols"
SIZE"1B"
BODY_TYPE"PLUMBING"
HDL_POWER"GND";
"A\NAC"4;
%"GND"
"1","(-4150,400)","0","mstr_symbols","I14";
;
VOLTAGE"0.0V"
CDS_LIB"mstr_symbols"
SIZE"1B"
BODY_TYPE"PLUMBING"
HDL_POWER"GND";
"A\NAC"5;
%"GND"
"1","(-5950,400)","0","mstr_symbols","I15";
;
VOLTAGE"0.0V"
CDS_LIB"mstr_symbols"
SIZE"1B"
BODY_TYPE"PLUMBING"
HDL_POWER"GND";
"A\NAC"6;
%"GND"
"1","(-450,1700)","0","mstr_symbols","I16";
;
VOLTAGE"0.0V"
CDS_LIB"mstr_symbols"
SIZE"1B"
BODY_TYPE"PLUMBING"
HDL_POWER"GND";
"A\NAC"7;
%"SKX_EXT_B"
"27","(-6725,2525)","0","chpset_lib","I17";
;
CDS_SEC"27"
LOCATION"U2D1"
PART_NUMBER"TBD"
MATERIAL"IC"
PACK_TYPE"BGA1"
SEC_TYPE"BGA1"
CDS_LIB"chpset_lib"
SEC"27"
CDS_LOCATION"U2D1";
"VSS<454>"
$PN"P49"6;
"VSS<455>"
$PN"CJ12"6;
"VSS<456>"
$PN"CJ10"6;
"VSS<457>"
$PN"CJ8"6;
"VSS<458>"
$PN"CJ6"6;
"VSS<459>"
$PN"CJ2"6;
"VSS<460>"
$PN"CH83"6;
"VSS<461>"
$PN"CH81"6;
"VSS<462>"
$PN"CH79"6;
"VSS<463>"
$PN"CH73"6;
"VSS<464>"
$PN"CH67"6;
"VSS<465>"
$PN"CH63"6;
"VSS<466>"
$PN"CH19"6;
"VSS<467>"
$PN"CH15"6;
"VSS<468>"
$PN"CH3"6;
"VSS<469>"
$PN"CH1"6;
"VSS<470>"
$PN"CG80"6;
"VSS<471>"
$PN"CG72"6;
"VSS<472>"
$PN"CG68"6;
"VSS<473>"
$PN"CG62"6;
"VSS<474>"
$PN"CG22"6;
"VSS<475>"
$PN"CG18"6;
"VSS<476>"
$PN"P51"6;
"VSS<477>"
$PN"CF83"6;
"VSS<478>"
$PN"CF77"6;
"VSS<479>"
$PN"CF71"6;
"VSS<480>"
$PN"CF69"6;
"VSS<481>"
$PN"CF63"6;
"VSS<482>"
$PN"CF9"6;
"VSS<483>"
$PN"P53"6;
"VSS<484>"
$PN"CE82"6;
"VSS<485>"
$PN"CE70"6;
"VSS<486>"
$PN"CE62"6;
"VSS<487>"
$PN"CE26"6;
"VSS<488>"
$PN"CE20"6;
"VSS<489>"
$PN"CE14"6;
"VSS<490>"
$PN"CE10"6;
"VSS<491>"
$PN"CD81"6;
"VSS<492>"
$PN"CD79"6;
"VSS<493>"
$PN"CD77"6;
"VSS<494>"
$PN"CD75"6;
"VSS<495>"
$PN"CD73"6;
"VSS<496>"
$PN"CD63"6;
"VSS<497>"
$PN"CD13"6;
"VSS<498>"
$PN"CD5"6;
"VSS<499>"
$PN"CC82"6;
"VSS<500>"
$PN"CC80"6;
"VSS<501>"
$PN"CC78"6;
"VSS<502>"
$PN"CC76"6;
"VSS<503>"
$PN"CC74"6;
"VSS<504>"
$PN"CC72"6;
"VSS<505>"
$PN"CC64"6;
"VSS<506>"
$PN"CC24"6;
"VSS<507>"
$PN"CC18"6;
"VSS<508>"
$PN"CC16"6;
"VSS<509>"
$PN"CC4"6;
"VSS<510>"
$PN"CB71"6;
"VSS<511>"
$PN"CB63"6;
"VSS<512>"
$PN"CB27"6;
"VSS<513>"
$PN"CB9"6;
"VSS<514>"
$PN"CB7"6;
"VSS<515>"
$PN"CA70"6;
"VSS<516>"
$PN"CA68"6;
"VSS<517>"
$PN"CA66"6;
"VSS<518>"
$PN"CA64"6;
"VSS<519>"
$PN"CA26"6;
"VSS<520>"
$PN"CA18"6;
"VSS<521>"
$PN"CA14"6;
"VSS<522>"
$PN"CA10"6;
"VSS<523>"
$PN"CA8"6;
"VSS<524>"
$PN"CA6"6;
"VSS<525>"
$PN"CA2"6;
"VSS<526>"
$PN"BY71"6;
"VSS<527>"
$PN"BY69"6;
"VSS<528>"
$PN"BY67"6;
"VSS<529>"
$PN"BY65"6;
"VSS<530>"
$PN"BY63"6;
"VSS<531>"
$PN"BY23"6;
"VSS<532>"
$PN"BY13"6;
"VSS<533>"
$PN"BY11"6;
"VSS<534>"
$PN"BW82"8;
"VSS<535>"
$PN"BW80"8;
"VSS<536>"
$PN"BW78"8;
"VSS<537>"
$PN"BW76"8;
"VSS<538>"
$PN"BW74"8;
"VSS<539>"
$PN"BW72"8;
"VSS<540>"
$PN"BW26"8;
"VSS<541>"
$PN"BW18"8;
"VSS<542>"
$PN"BW16"8;
"VSS<543>"
$PN"BW14"8;
"VSS<544>"
$PN"BW12"8;
"VSS<545>"
$PN"P55"8;
"VSS<546>"
$PN"BW6"8;
"VSS<547>"
$PN"BV25"8;
"VSS<548>"
$PN"BV17"8;
"VSS<549>"
$PN"BU10"8;
"VSS<550>"
$PN"BV5"8;
"VSS<551>"
$PN"BU8"8;
"VSS<552>"
$PN"BT25"8;
"VSS<553>"
$PN"BT23"8;
"VSS<554>"
$PN"BT21"8;
"VSS<555>"
$PN"BT5"8;
"VSS<556>"
$PN"BT3"8;
"VSS<557>"
$PN"BR82"8;
"VSS<558>"
$PN"BR80"8;
"VSS<559>"
$PN"BR78"8;
"VSS<560>"
$PN"BR76"8;
"VSS<561>"
$PN"BR74"8;
"VSS<562>"
$PN"BR72"8;
"VSS<563>"
$PN"BR70"8;
"VSS<564>"
$PN"BR68"8;
"VSS<565>"
$PN"BR66"8;
"VSS<566>"
$PN"BR64"8;
"VSS<567>"
$PN"P57"8;
"VSS<568>"
$PN"BR16"8;
"VSS<569>"
$PN"BR10"8;
"VSS<570>"
$PN"BR6"8;
"VSS<571>"
$PN"BP27"8;
"VSS<572>"
$PN"BP3"8;
"VSS<573>"
$PN"BN26"8;
"VSS<574>"
$PN"BN20"8;
"VSS<575>"
$PN"BN10"8;
"VSS<576>"
$PN"BN6"8;
"VSS<577>"
$PN"BM25"8;
"VSS<578>"
$PN"P59"8;
"VSS<579>"
$PN"BM15"8;
"VSS<580>"
$PN"BM13"8;
"VSS<581>"
$PN"BM9"8;
"VSS<582>"
$PN"BL82"8;
"VSS<583>"
$PN"BL80"8;
"VSS<584>"
$PN"BL78"8;
"VSS<585>"
$PN"BL76"8;
"VSS<586>"
$PN"BL74"8;
"VSS<587>"
$PN"BL72"8;
"VSS<588>"
$PN"BL70"8;
"VSS<589>"
$PN"BL68"8;
"VSS<590>"
$PN"BL66"8;
"VSS<591>"
$PN"BL64"8;
"VSS<592>"
$PN"BL24"8;
"VSS<593>"
$PN"BL22"8;
"VSS<594>"
$PN"P61"8;
"VSS<595>"
$PN"BL12"8;
"VSS<596>"
$PN"BL10"8;
"VSS<597>"
$PN"BL6"8;
"VSS<598>"
$PN"BK19"8;
"VSS<599>"
$PN"BK11"8;
"VSS<600>"
$PN"BK7"8;
"VSS<601>"
$PN"BK3"8;
"VSS<602>"
$PN"BJ6"8;
"VSS<603>"
$PN"BJ4"8;
"VSS<604>"
$PN"BH21"8;
"VSS<605>"
$PN"BH15"8;
"VSS<606>"
$PN"BH11"8;
"VSS<607>"
$PN"BH9"8;
"VSS<608>"
$PN"BH7"8;
"VSS<609>"
$PN"BG82"8;
"VSS<610>"
$PN"BG80"8;
"VSS<611>"
$PN"BG78"8;
"VSS<612>"
$PN"BG76"8;
"VSS<613>"
$PN"BG74"8;
%"SKX_EXT_B"
"28","(-4925,2525)","0","chpset_lib","I18";
;
CDS_SEC"28"
LOCATION"U2D1"
PART_NUMBER"TBD"
MATERIAL"IC"
PACK_TYPE"BGA1"
SEC_TYPE"BGA1"
CDS_LIB"chpset_lib"
SEC"28"
CDS_LOCATION"U2D1";
"VSS<294>"
$PN"DA46"5;
"VSS<295>"
$PN"DA44"5;
"VSS<296>"
$PN"DA38"5;
"VSS<297>"
$PN"DA36"5;
"VSS<298>"
$PN"DA34"5;
"VSS<299>"
$PN"DA32"5;
"VSS<300>"
$PN"DA30"5;
"VSS<301>"
$PN"DA28"5;
"VSS<302>"
$PN"DA26"5;
"VSS<303>"
$PN"DA18"5;
"VSS<304>"
$PN"H53"5;
"VSS<305>"
$PN"DA6"5;
"VSS<306>"
$PN"CY85"5;
"VSS<307>"
$PN"CY83"5;
"VSS<308>"
$PN"CY77"5;
"VSS<309>"
$PN"CY75"5;
"VSS<310>"
$PN"CY69"5;
"VSS<311>"
$PN"CY65"5;
"VSS<312>"
$PN"CY61"5;
"VSS<313>"
$PN"CY59"5;
"VSS<314>"
$PN"CY51"5;
"VSS<315>"
$PN"CY45"5;
"VSS<316>"
$PN"CY41"5;
"VSS<317>"
$PN"CY21"5;
"VSS<318>"
$PN"CY15"5;
"VSS<319>"
$PN"CY13"5;
"VSS<320>"
$PN"CY9"5;
"VSS<321>"
$PN"CY1"5;
"VSS<322>"
$PN"CW82"5;
"VSS<323>"
$PN"CW78"5;
"VSS<324>"
$PN"CW74"5;
"VSS<325>"
$PN"CW68"5;
"VSS<326>"
$PN"CW66"5;
"VSS<327>"
$PN"CW64"5;
"VSS<328>"
$PN"CW54"5;
"VSS<329>"
$PN"CW52"5;
"VSS<330>"
$PN"CW42"5;
"VSS<331>"
$PN"CW40"5;
"VSS<332>"
$PN"CW38"5;
"VSS<333>"
$PN"CW32"5;
"VSS<334>"
$PN"CW26"5;
"VSS<335>"
$PN"CW12"5;
"VSS<336>"
$PN"CV83"5;
"VSS<337>"
$PN"CV81"5;
"VSS<338>"
$PN"CV79"5;
"VSS<339>"
$PN"CV73"5;
"VSS<340>"
$PN"CV67"5;
"VSS<341>"
$PN"CV63"5;
"VSS<342>"
$PN"CV55"5;
"VSS<343>"
$PN"CV53"5;
"VSS<344>"
$PN"CV41"5;
"VSS<345>"
$PN"CV39"5;
"VSS<346>"
$PN"CV37"5;
"VSS<347>"
$PN"CV33"5;
"VSS<348>"
$PN"CV31"5;
"VSS<349>"
$PN"CV27"5;
"VSS<350>"
$PN"CV25"5;
"VSS<351>"
$PN"CV17"5;
"VSS<352>"
$PN"H55"5;
"VSS<353>"
$PN"CV1"5;
"VSS<354>"
$PN"CU86"5;
"VSS<355>"
$PN"CU82"5;
"VSS<356>"
$PN"CU80"5;
"VSS<357>"
$PN"CU78"5;
"VSS<358>"
$PN"CU76"5;
"VSS<359>"
$PN"CU68"5;
"VSS<360>"
$PN"CU62"5;
"VSS<361>"
$PN"CU56"5;
"VSS<362>"
$PN"CU36"5;
"VSS<363>"
$PN"CU34"5;
"VSS<364>"
$PN"CU30"5;
"VSS<365>"
$PN"CU28"5;
"VSS<366>"
$PN"CU22"5;
"VSS<367>"
$PN"CU4"5;
"VSS<368>"
$PN"CT85"5;
"VSS<369>"
$PN"CT83"5;
"VSS<370>"
$PN"CT79"5;
"VSS<371>"
$PN"CT73"5;
"VSS<372>"
$PN"CT57"5;
"VSS<373>"
$PN"CT35"5;
"VSS<374>"
$PN"CT33"1;
"VSS<375>"
$PN"CT29"1;
"VSS<376>"
$PN"CT27"1;
"VSS<377>"
$PN"CT19"1;
"VSS<378>"
$PN"CT13"1;
"VSS<379>"
$PN"H57"1;
"VSS<380>"
$PN"CR86"1;
"VSS<381>"
$PN"CR78"1;
"VSS<382>"
$PN"CR68"1;
"VSS<383>"
$PN"CR66"1;
"VSS<384>"
$PN"CR64"1;
"VSS<385>"
$PN"CR62"1;
"VSS<386>"
$PN"CR58"1;
"VSS<387>"
$PN"CR32"1;
"VSS<388>"
$PN"CR24"1;
"VSS<389>"
$PN"CR22"1;
"VSS<390>"
$PN"CR10"1;
"VSS<391>"
$PN"CR6"1;
"VSS<392>"
$PN"CP83"1;
"VSS<393>"
$PN"CP81"1;
"VSS<394>"
$PN"CP75"1;
"VSS<395>"
$PN"CP73"1;
"VSS<396>"
$PN"CP69"1;
"VSS<397>"
$PN"CP59"1;
"VSS<398>"
$PN"CP25"1;
"VSS<399>"
$PN"H59"1;
"VSS<400>"
$PN"CP1"1;
"VSS<401>"
$PN"CN78"1;
"VSS<402>"
$PN"CN68"1;
"VSS<403>"
$PN"CN62"1;
"VSS<404>"
$PN"CN60"1;
"VSS<405>"
$PN"CN32"1;
"VSS<406>"
$PN"CN26"1;
"VSS<407>"
$PN"H61"1;
"VSS<408>"
$PN"CN12"1;
"VSS<409>"
$PN"CN2"1;
"VSS<410>"
$PN"CM85"1;
"VSS<411>"
$PN"CM83"1;
"VSS<412>"
$PN"CM77"1;
"VSS<413>"
$PN"CM73"1;
"VSS<414>"
$PN"CM67"1;
"VSS<415>"
$PN"CM63"1;
"VSS<416>"
$PN"CM61"1;
"VSS<417>"
$PN"CM31"1;
"VSS<418>"
$PN"CM5"1;
"VSS<419>"
$PN"CM29"1;
"VSS<420>"
$PN"CM19"1;
"VSS<421>"
$PN"CL80"1;
"VSS<422>"
$PN"CL78"1;
"VSS<423>"
$PN"CL76"1;
"VSS<424>"
$PN"CL74"1;
"VSS<425>"
$PN"CL66"1;
"VSS<426>"
$PN"CL64"1;
"VSS<427>"
$PN"CL62"1;
"VSS<428>"
$PN"H63"1;
"VSS<429>"
$PN"P45"1;
"VSS<430>"
$PN"CL18"1;
"VSS<431>"
$PN"CL14"1;
"VSS<432>"
$PN"CL8"1;
"VSS<433>"
$PN"CK85"1;
"VSS<434>"
$PN"CK83"1;
"VSS<435>"
$PN"CK75"1;
"VSS<436>"
$PN"CK73"1;
"VSS<437>"
$PN"CK71"1;
"VSS<438>"
$PN"CK69"1;
"VSS<439>"
$PN"CK67"1;
"VSS<440>"
$PN"CK65"1;
"VSS<441>"
$PN"CK63"1;
"VSS<442>"
$PN"CK27"1;
"VSS<443>"
$PN"CK21"1;
"VSS<444>"
$PN"CK15"1;
"VSS<445>"
$PN"CK11"1;
"VSS<446>"
$PN"CJ86"1;
"VSS<447>"
$PN"CJ84"1;
"VSS<448>"
$PN"CJ82"1;
"VSS<449>"
$PN"CJ78"1;
"VSS<450>"
$PN"CJ76"1;
"VSS<451>"
$PN"CJ74"1;
"VSS<452>"
$PN"CJ62"1;
"VSS<453>"
$PN"P47"1;
%"SKX_EXT_B"
"29","(-3050,2525)","0","chpset_lib","I19";
;
CDS_SEC"29"
LOCATION"U2D1"
PART_NUMBER"TBD"
MATERIAL"IC"
PACK_TYPE"BGA1"
SEC_TYPE"BGA1"
CDS_LIB"chpset_lib"
SEC"29"
CDS_LOCATION"U2D1";
"VSS<134>"
$PN"DN72"4;
"VSS<135>"
$PN"DN68"4;
"VSS<136>"
$PN"DN38"4;
"VSS<137>"
$PN"DN32"4;
"VSS<138>"
$PN"DN26"4;
"VSS<139>"
$PN"DN22"4;
"VSS<140>"
$PN"DN12"4;
"VSS<141>"
$PN"BH17"4;
"VSS<142>"
$PN"DN2"4;
"VSS<143>"
$PN"DM83"4;
"VSS<144>"
$PN"DM77"4;
"VSS<145>"
$PN"DM73"4;
"VSS<146>"
$PN"DM65"4;
"VSS<147>"
$PN"DM39"4;
"VSS<148>"
$PN"DM37"4;
"VSS<149>"
$PN"DM33"4;
"VSS<150>"
$PN"DM31"4;
"VSS<151>"
$PN"DM27"4;
"VSS<152>"
$PN"DM25"4;
"VSS<153>"
$PN"H45"4;
"VSS<154>"
$PN"DM15"4;
"VSS<155>"
$PN"DL80"4;
"VSS<156>"
$PN"DL78"4;
"VSS<157>"
$PN"DL76"4;
"VSS<158>"
$PN"DL74"4;
"VSS<159>"
$PN"DL70"4;
"VSS<160>"
$PN"DL68"4;
"VSS<161>"
$PN"DL40"4;
"VSS<162>"
$PN"DL36"4;
"VSS<163>"
$PN"DL34"4;
"VSS<164>"
$PN"DL30"4;
"VSS<165>"
$PN"DL28"4;
"VSS<166>"
$PN"DL24"4;
"VSS<167>"
$PN"DL22"4;
"VSS<168>"
$PN"DL4"4;
"VSS<169>"
$PN"DL18"4;
"VSS<170>"
$PN"DL16"4;
"VSS<171>"
$PN"DK85"4;
"VSS<172>"
$PN"DK83"4;
"VSS<173>"
$PN"DK77"4;
"VSS<174>"
$PN"DK75"4;
"VSS<175>"
$PN"DK73"4;
"VSS<176>"
$PN"DK41"4;
"VSS<177>"
$PN"DK39"4;
"VSS<178>"
$PN"DK35"4;
"VSS<179>"
$PN"DK29"4;
"VSS<180>"
$PN"DK23"4;
"VSS<181>"
$PN"DK7"4;
"VSS<182>"
$PN"DJ84"4;
"VSS<183>"
$PN"DJ82"4;
"VSS<184>"
$PN"DJ78"4;
"VSS<185>"
$PN"DJ74"4;
"VSS<186>"
$PN"DJ68"4;
"VSS<187>"
$PN"DJ42"4;
"VSS<188>"
$PN"DJ38"4;
"VSS<189>"
$PN"DJ22"4;
"VSS<190>"
$PN"H47"4;
"VSS<191>"
$PN"DJ10"4;
"VSS<192>"
$PN"DJ2"4;
"VSS<193>"
$PN"DH83"4;
"VSS<194>"
$PN"DH81"4;
"VSS<195>"
$PN"DH79"4;
"VSS<196>"
$PN"DH73"4;
"VSS<197>"
$PN"DH71"4;
"VSS<198>"
$PN"DH67"4;
"VSS<199>"
$PN"DH41"4;
"VSS<200>"
$PN"DH37"4;
"VSS<201>"
$PN"DH35"4;
"VSS<202>"
$PN"DH33"4;
"VSS<203>"
$PN"DH31"4;
"VSS<204>"
$PN"DH29"4;
"VSS<205>"
$PN"DH27"4;
"VSS<206>"
$PN"DH25"4;
"VSS<207>"
$PN"DH23"4;
"VSS<208>"
$PN"DH15"4;
"VSS<209>"
$PN"DH13"4;
"VSS<210>"
$PN"DG82"4;
"VSS<211>"
$PN"DG80"4;
"VSS<212>"
$PN"DG78"4;
"VSS<213>"
$PN"DG76"4;
"VSS<214>"
$PN"DG68"2;
"VSS<215>"
$PN"DG66"2;
"VSS<216>"
$PN"DG24"2;
"VSS<217>"
$PN"DG16"2;
"VSS<218>"
$PN"DG14"2;
"VSS<219>"
$PN"H49"2;
"VSS<220>"
$PN"DG2"2;
"VSS<221>"
$PN"DF85"2;
"VSS<222>"
$PN"DF83"2;
"VSS<223>"
$PN"DF79"2;
"VSS<224>"
$PN"DF73"2;
"VSS<225>"
$PN"DF69"2;
"VSS<226>"
$PN"DF65"2;
"VSS<227>"
$PN"DF41"2;
"VSS<228>"
$PN"DF39"2;
"VSS<229>"
$PN"DF37"2;
"VSS<230>"
$PN"DF35"2;
"VSS<231>"
$PN"DF29"2;
"VSS<232>"
$PN"DF19"2;
"VSS<233>"
$PN"H51"2;
"VSS<234>"
$PN"DF7"2;
"VSS<235>"
$PN"DF5"2;
"VSS<236>"
$PN"DE78"2;
"VSS<237>"
$PN"DE72"2;
"VSS<238>"
$PN"DE70"2;
"VSS<239>"
$PN"DE64"2;
"VSS<240>"
$PN"DE36"2;
"VSS<241>"
$PN"DE34"2;
"VSS<242>"
$PN"DE30"2;
"VSS<243>"
$PN"DE28"2;
"VSS<244>"
$PN"DE24"2;
"VSS<245>"
$PN"DE20"2;
"VSS<246>"
$PN"DE18"2;
"VSS<247>"
$PN"DE8"2;
"VSS<248>"
$PN"DE6"2;
"VSS<249>"
$PN"DD83"2;
"VSS<250>"
$PN"DD81"2;
"VSS<251>"
$PN"DD75"2;
"VSS<252>"
$PN"DD73"2;
"VSS<253>"
$PN"DD71"2;
"VSS<254>"
$PN"DD37"2;
"VSS<255>"
$PN"DD33"2;
"VSS<256>"
$PN"DD31"2;
"VSS<257>"
$PN"DD27"2;
"VSS<258>"
$PN"DD23"2;
"VSS<259>"
$PN"DD11"2;
"VSS<260>"
$PN"DC86"2;
"VSS<261>"
$PN"DC84"2;
"VSS<262>"
$PN"DC78"2;
"VSS<263>"
$PN"DC70"2;
"VSS<264>"
$PN"DC68"2;
"VSS<265>"
$PN"DC66"2;
"VSS<266>"
$PN"DC64"2;
"VSS<267>"
$PN"DC42"2;
"VSS<268>"
$PN"DC38"2;
"VSS<269>"
$PN"DC32"2;
"VSS<270>"
$PN"DC26"2;
"VSS<271>"
$PN"DC24"2;
"VSS<272>"
$PN"DC14"2;
"VSS<273>"
$PN"DB85"2;
"VSS<274>"
$PN"DB83"2;
"VSS<275>"
$PN"DB77"2;
"VSS<276>"
$PN"DB73"2;
"VSS<277>"
$PN"DB49"2;
"VSS<278>"
$PN"DB47"2;
"VSS<279>"
$PN"DB41"2;
"VSS<280>"
$PN"DB39"2;
"VSS<281>"
$PN"DB25"2;
"VSS<282>"
$PN"DB23"2;
"VSS<283>"
$PN"DB17"2;
"VSS<284>"
$PN"DB13"2;
"VSS<285>"
$PN"DB3"2;
"VSS<286>"
$PN"DA80"2;
"VSS<287>"
$PN"DA78"2;
"VSS<288>"
$PN"DA76"2;
"VSS<289>"
$PN"DA74"2;
"VSS<290>"
$PN"DA70"2;
"VSS<291>"
$PN"DA64"2;
"VSS<292>"
$PN"DA50"2;
"VSS<293>"
$PN"DA48"2;
%"SKX_EXT_B"
"30","(-1225,2550)","0","chpset_lib","I20";
;
CDS_SEC"30"
LOCATION"U2D1"
PART_NUMBER"TBD"
MATERIAL"IC"
PACK_TYPE"BGA1"
SEC_TYPE"BGA1"
CDS_LIB"chpset_lib"
SEC"30"
CDS_LOCATION"U2D1";
"VSS<0>"
$PN"EF79"7;
"VSS<1>"
$PN"EF75"7;
"VSS<2>"
$PN"EF71"7;
"VSS<3>"
$PN"EE78"7;
"VSS<4>"
$PN"EE76"7;
"VSS<5>"
$PN"EE70"7;
"VSS<6>"
$PN"EE36"7;
"VSS<7>"
$PN"EE34"7;
"VSS<8>"
$PN"EE30"7;
"VSS<9>"
$PN"EE28"7;
"VSS<10>"
$PN"EE24"7;
"VSS<11>"
$PN"ED77"7;
"VSS<12>"
$PN"ED35"7;
"VSS<13>"
$PN"ED29"7;
"VSS<14>"
$PN"ED23"7;
"VSS<15>"
$PN"ED15"7;
"VSS<16>"
$PN"ED11"7;
"VSS<17>"
$PN"EC76"7;
"VSS<18>"
$PN"EC74"7;
"VSS<19>"
$PN"EC72"7;
"VSS<20>"
$PN"EC70"7;
"VSS<21>"
$PN"EC10"7;
"VSS<22>"
$PN"EB69"7;
"VSS<23>"
$PN"EB65"7;
"VSS<24>"
$PN"EB41"7;
"VSS<25>"
$PN"EB39"7;
"VSS<26>"
$PN"EB37"7;
"VSS<27>"
$PN"EB35"7;
"VSS<28>"
$PN"EB33"7;
"VSS<29>"
$PN"EB31"7;
"VSS<30>"
$PN"EB29"7;
"VSS<31>"
$PN"EB27"7;
"VSS<32>"
$PN"EB25"7;
"VSS<33>"
$PN"EB23"7;
"VSS<34>"
$PN"BR18"7;
"VSS<35>"
$PN"EB13"7;
"VSS<36>"
$PN"EA82"7;
"VSS<37>"
$PN"EA80"7;
"VSS<38>"
$PN"EA78"7;
"VSS<39>"
$PN"EA76"7;
"VSS<40>"
$PN"EA70"7;
"VSS<41>"
$PN"EA64"7;
"VSS<42>"
$PN"EA42"7;
"VSS<43>"
$PN"EA22"7;
"VSS<44>"
$PN"EA20"7;
"VSS<45>"
$PN"EA16"7;
"VSS<46>"
$PN"J16"7;
"VSS<47>"
$PN"EA6"7;
"VSS<48>"
$PN"DY75"7;
"VSS<49>"
$PN"DY71"7;
"VSS<50>"
$PN"DY41"7;
"VSS<51>"
$PN"DY35"7;
"VSS<52>"
$PN"DY29"7;
"VSS<53>"
$PN"DY23"7;
"VSS<54>"
$PN"DY19"3;
"VSS<55>"
$PN"DY5"3;
"VSS<56>"
$PN"DW84"3;
"VSS<57>"
$PN"DW82"3;
"VSS<58>"
$PN"DW8"3;
"VSS<59>"
$PN"DW76"3;
"VSS<60>"
$PN"DW74"3;
"VSS<61>"
$PN"DW72"3;
"VSS<62>"
$PN"DW70"3;
"VSS<63>"
$PN"DW68"3;
"VSS<64>"
$PN"DW66"3;
"VSS<65>"
$PN"DW64"3;
"VSS<66>"
$PN"DW40"3;
"VSS<67>"
$PN"DW36"3;
"VSS<68>"
$PN"DW34"3;
"VSS<69>"
$PN"DW30"3;
"VSS<70>"
$PN"DW28"3;
"VSS<71>"
$PN"DW24"3;
"VSS<72>"
$PN"DW20"3;
"VSS<73>"
$PN"DW12"3;
"VSS<74>"
$PN"DV81"3;
"VSS<75>"
$PN"DV77"3;
"VSS<76>"
$PN"DV73"3;
"VSS<77>"
$PN"DV39"3;
"VSS<78>"
$PN"DV37"3;
"VSS<79>"
$PN"DV33"3;
"VSS<80>"
$PN"DV31"3;
"VSS<81>"
$PN"DV27"3;
"VSS<82>"
$PN"DV25"3;
"VSS<83>"
$PN"DV21"3;
"VSS<84>"
$PN"DU84"3;
"VSS<85>"
$PN"DU82"3;
"VSS<86>"
$PN"DU80"3;
"VSS<87>"
$PN"DU78"3;
"VSS<88>"
$PN"DU72"3;
"VSS<89>"
$PN"DU70"3;
"VSS<90>"
$PN"DU38"3;
"VSS<91>"
$PN"DU32"3;
"VSS<92>"
$PN"DU26"3;
"VSS<93>"
$PN"DU22"3;
"VSS<94>"
$PN"CN14"3;
"VSS<95>"
$PN"DU14"3;
"VSS<96>"
$PN"DU10"3;
"VSS<97>"
$PN"DT85"3;
"VSS<98>"
$PN"DT83"3;
"VSS<99>"
$PN"DT79"3;
"VSS<100>"
$PN"DT69"3;
"VSS<101>"
$PN"DT65"3;
"VSS<102>"
$PN"DH21"3;
"VSS<103>"
$PN"DT17"3;
"VSS<104>"
$PN"DT3"3;
"VSS<105>"
$PN"DR78"3;
"VSS<106>"
$PN"DR76"3;
"VSS<107>"
$PN"DR74"3;
"VSS<108>"
$PN"DR72"3;
"VSS<109>"
$PN"DR70"3;
"VSS<110>"
$PN"DR68"3;
"VSS<111>"
$PN"DR66"3;
"VSS<112>"
$PN"DR42"3;
"VSS<113>"
$PN"DR40"3;
"VSS<114>"
$PN"DR38"3;
"VSS<115>"
$PN"DR36"3;
"VSS<116>"
$PN"DR34"3;
"VSS<117>"
$PN"DR32"3;
"VSS<118>"
$PN"DR30"3;
"VSS<119>"
$PN"DR28"3;
"VSS<120>"
$PN"DR26"3;
"VSS<121>"
$PN"DR24"3;
"VSS<122>"
$PN"DR22"3;
"VSS<123>"
$PN"DR20"3;
"VSS<124>"
$PN"CL22"3;
"VSS<125>"
$PN"CA20"3;
"VSS<126>"
$PN"DR6"3;
"VSS<127>"
$PN"BR26"3;
"VSS<128>"
$PN"DP83"3;
"VSS<129>"
$PN"DP81"3;
"VSS<130>"
$PN"DP71"3;
"VSS<131>"
$PN"DP69"3;
"VSS<132>"
$PN"DP67"3;
"VSS<133>"
$PN"DN78"3;
%"GND"
"1","(-7475,400)","0","mstr_symbols","I9";
;
VOLTAGE"0.0V"
CDS_LIB"mstr_symbols"
SIZE"1B"
BODY_TYPE"PLUMBING"
HDL_POWER"GND";
"A\NAC"8;
END.
